# S9S_MB_2U (Grand Teton) — schematic netlist excerpt (pin names and nets, part order shuffled) for the footprints in the layout excerpt that follows; sources: Cadence DE-HDL packaged netlist, KiCad conversion of 03242023_DA0F0TMBIJ0_F0T_Motherboard_J_brd_V01_OCP.brd

R3504  Q_RES  4.7K 5% CHIP  pkg 0402LF  page 147 : A = P3V3_AUX ; B = GPU_FPGA_EROT_FATALERR_ISO_N
R2121  Q_RES  4.7K 5% CHIP  pkg 0402LF  page 190 : A = P3V3_AUX ; B = RST_PCIE_PCH_DEV_BUF_M2_0_PERST

(kicad_pcb
	(version 20260206)
	(generator "pcbnew")
	(generator_version "10.0")
	(general
		(thickness 1.6)
		(legacy_teardrops no)
	)
	(paper "A4")
	(title_block
		(title "03242023_DA0F0TMBIJ0_F0T_Motherboard_J_brd_V01_OCP.brd")
		(comment 1 "Grand Teton / footprints 2327-2328 of 6105")
	)
	(layers
		(0 "F.Cu" signal "TOP")
		(4 "In1.Cu" signal "GND")
		(6 "In2.Cu" signal "IN1")
		(8 "In3.Cu" signal "GND1")
		(10 "In4.Cu" signal "IN2")
		(12 "In5.Cu" signal "GND2")
		(14 "In6.Cu" signal "IN3")
		(16 "In7.Cu" signal "GND3")
		(18 "In8.Cu" signal "VCC")
		(20 "In9.Cu" signal "VCC1")
		(22 "In10.Cu" signal "GND4")
		(24 "In11.Cu" signal "IN4")
		(26 "In12.Cu" signal "GND5")
		(28 "In13.Cu" signal "IN5")
		(30 "In14.Cu" signal "GND6")
		(32 "In15.Cu" signal "IN6")
		(34 "In16.Cu" signal "GND7")
		(2 "B.Cu" signal "BOTTOM")
		(9 "F.Adhes" user "F.Adhesive")
		(11 "B.Adhes" user "B.Adhesive")
		(13 "F.Paste" user "Package Geometry/Pastemask Top")
		(15 "B.Paste" user "Package Geometry/Pastemask Bottom")
		(5 "F.SilkS" user "Ref Des/Silkscreen Top")
		(7 "B.SilkS" user "Ref Des/Silkscreen Bottom")
		(1 "F.Mask" user "Board Geometry/Soldermask Top")
		(3 "B.Mask" user "Board Geometry/Soldermask Bottom")
		(17 "Dwgs.User" user "User.Drawings")
		(19 "Cmts.User" user "User.Comments")
		(21 "Eco1.User" user "User.Eco1")
		(23 "Eco2.User" user "User.Eco2")
		(25 "Edge.Cuts" user "Board Geometry/Outline")
		(27 "Margin" user)
		(31 "F.CrtYd" user "Package Geometry/Place Bound Top")
		(29 "B.CrtYd" user "Package Geometry/Place Bound Bottom")
		(35 "F.Fab" user "Ref Des/Assembly Top")
		(33 "B.Fab" user "Ref Des/Assembly Bottom")
	)
	(footprint ""
		(layer "F.Cu")
		(at 140.00988 -40.985948 180)
		(property "Reference" "R2121"
			(at 0 0 180)
			(layer "F.SilkS")
			(hide yes)
			(effects
				(font
					(size 1.27 1.27)
				)
			)
		)
		(property "Value" ""
			(at 0 0 180)
			(layer "F.Fab")
			(effects
				(font
					(size 1.27 1.27)
				)
			)
		)
		(duplicate_pad_numbers_are_jumpers no)
		(fp_line
			(start 0.7874 0.4064)
			(end -0.7874 0.4064)
			(stroke
				(width 0.1524)
				(type default)
			)
			(layer "F.SilkS")
		)
		(fp_line
			(start 0.7874 -0.4064)
			(end 0.7874 0.4064)
			(stroke
				(width 0.1524)
				(type default)
			)
			(layer "F.SilkS")
		)
		(fp_line
			(start -0.7874 0.4064)
			(end -0.7874 -0.4064)
			(stroke
				(width 0.1524)
				(type default)
			)
			(layer "F.SilkS")
		)
		(fp_line
			(start -0.7874 -0.4064)
			(end 0.7874 -0.4064)
			(stroke
				(width 0.1524)
				(type default)
			)
			(layer "F.SilkS")
		)
		(fp_line
			(start 0.67945 0.3048)
			(end 0.120396 0.3048)
			(stroke
				(width 0.1)
				(type default)
			)
			(layer "F.Fab")
		)
		(fp_line
			(start 0.67945 -0.3048)
			(end 0.67945 0.3048)
			(stroke
				(width 0.1)
				(type default)
			)
			(layer "F.Fab")
		)
		(fp_line
			(start 0.12065 -0.2794)
			(end 0.12065 -0.3048)
			(stroke
				(width 0.1)
				(type default)
			)
			(layer "F.Fab")
		)
		(fp_line
			(start 0.12065 -0.3048)
			(end 0.67945 -0.3048)
			(stroke
				(width 0.1)
				(type default)
			)
			(layer "F.Fab")
		)
		(fp_line
			(start 0.120396 0.3048)
			(end 0.120396 0.2794)
			(stroke
				(width 0.1)
				(type default)
			)
			(layer "F.Fab")
		)
		(fp_line
			(start 0.120396 0.2794)
			(end -0.12065 0.2794)
			(stroke
				(width 0.1)
				(type default)
			)
			(layer "F.Fab")
		)
		(fp_line
			(start -0.12065 0.3048)
			(end -0.67945 0.3048)
			(stroke
				(width 0.1)
				(type default)
			)
			(layer "F.Fab")
		)
		(fp_line
			(start -0.12065 0.2794)
			(end -0.12065 0.3048)
			(stroke
				(width 0.1)
				(type default)
			)
			(layer "F.Fab")
		)
		(fp_line
			(start -0.12065 -0.2794)
			(end 0.12065 -0.2794)
			(stroke
				(width 0.1)
				(type default)
			)
			(layer "F.Fab")
		)
		(fp_line
			(start -0.12065 -0.305054)
			(end -0.12065 -0.2794)
			(stroke
				(width 0.1)
				(type default)
			)
			(layer "F.Fab")
		)
		(fp_line
			(start -0.67945 0.3048)
			(end -0.67945 -0.305054)
			(stroke
				(width 0.1)
				(type default)
			)
			(layer "F.Fab")
		)
		(fp_line
			(start -0.67945 -0.305054)
			(end -0.12065 -0.305054)
			(stroke
				(width 0.1)
				(type default)
			)
			(layer "F.Fab")
		)
		(pad "1" smd circle
			(at -0.40005 0 180)
			(size 0 0)
			(layers "F.Cu" "F.Mask" "F.Paste")
			(net "P3V3_AUX")
		)
		(pad "2" smd circle
			(at 0.40005 0 180)
			(size 0 0)
			(layers "F.Cu" "F.Mask" "F.Paste")
			(net "RST_PCIE_PCH_DEV_BUF_M2_0_PERST")
		)
	)
	(footprint ""
		(layer "F.Cu")
		(at 24.069802 -410.418534)
		(property "Reference" "R3504"
			(at 0 0 0)
			(layer "F.SilkS")
			(hide yes)
			(effects
				(font
					(size 1.27 1.27)
				)
			)
		)
		(property "Value" ""
			(at 0 0 0)
			(layer "F.Fab")
			(effects
				(font
					(size 1.27 1.27)
				)
			)
		)
		(duplicate_pad_numbers_are_jumpers no)
		(fp_line
			(start -0.7874 -0.4064)
			(end 0.7874 -0.4064)
			(stroke
				(width 0.1524)
				(type default)
			)
			(layer "F.SilkS")
		)
		(fp_line
			(start -0.7874 0.4064)
			(end -0.7874 -0.4064)
			(stroke
				(width 0.1524)
				(type default)
			)
			(layer "F.SilkS")
		)
		(fp_line
			(start 0.7874 -0.4064)
			(end 0.7874 0.4064)
			(stroke
				(width 0.1524)
				(type default)
			)
			(layer "F.SilkS")
		)
		(fp_line
			(start 0.7874 0.4064)
			(end -0.7874 0.4064)
			(stroke
				(width 0.1524)
				(type default)
			)
			(layer "F.SilkS")
		)
		(fp_line
			(start -0.67945 -0.305054)
			(end -0.12065 -0.305054)
			(stroke
				(width 0.1)
				(type default)
			)
			(layer "F.Fab")
		)
		(fp_line
			(start -0.67945 0.3048)
			(end -0.67945 -0.305054)
			(stroke
				(width 0.1)
				(type default)
			)
			(layer "F.Fab")
		)
		(fp_line
			(start -0.12065 -0.305054)
			(end -0.12065 -0.2794)
			(stroke
				(width 0.1)
				(type default)
			)
			(layer "F.Fab")
		)
		(fp_line
			(start -0.12065 -0.2794)
			(end 0.12065 -0.2794)
			(stroke
				(width 0.1)
				(type default)
			)
			(layer "F.Fab")
		)
		(fp_line
			(start -0.12065 0.2794)
			(end -0.12065 0.3048)
			(stroke
				(width 0.1)
				(type default)
			)
			(layer "F.Fab")
		)
		(fp_line
			(start -0.12065 0.3048)
			(end -0.67945 0.3048)
			(stroke
				(width 0.1)
				(type default)
			)
			(layer "F.Fab")
		)
		(fp_line
			(start 0.120396 0.2794)
			(end -0.12065 0.2794)
			(stroke
				(width 0.1)
				(type default)
			)
			(layer "F.Fab")
		)
		(fp_line
			(start 0.120396 0.3048)
			(end 0.120396 0.2794)
			(stroke
				(width 0.1)
				(type default)
			)
			(layer "F.Fab")
		)
		(fp_line
			(start 0.12065 -0.3048)
			(end 0.67945 -0.3048)
			(stroke
				(width 0.1)
				(type default)
			)
			(layer "F.Fab")
		)
		(fp_line
			(start 0.12065 -0.2794)
			(end 0.12065 -0.3048)
			(stroke
				(width 0.1)
				(type default)
			)
			(layer "F.Fab")
		)
		(fp_line
			(start 0.67945 -0.3048)
			(end 0.67945 0.3048)
			(stroke
				(width 0.1)
				(type default)
			)
			(layer "F.Fab")
		)
		(fp_line
			(start 0.67945 0.3048)
			(end 0.120396 0.3048)
			(stroke
				(width 0.1)
				(type default)
			)
			(layer "F.Fab")
		)
		(pad "1" smd circle
			(at -0.40005 0)
			(size 0 0)
			(layers "F.Cu" "F.Mask" "F.Paste")
			(net "P3V3_AUX")
		)
		(pad "2" smd circle
			(at 0.40005 0)
			(size 0 0)
			(layers "F.Cu" "F.Mask" "F.Paste")
			(net "GPU_FPGA_EROT_FATALERR_ISO_N")
		)
	)
)
